(kicad_pcb
	(version 20260206)
	(generator "pcbnew")
	(generator_version "10.0")
	(general
		(thickness 1.6)
		(legacy_teardrops no)
	)
	(paper "A4")
	(title_block
		(title "9054_F0T_PDB_BD_GPU_F_V04_1213_1550_OCP.brd")
		(comment 1 "Grand Teton / footprints 496-502 of 608")
	)
	(layers
		(0 "F.Cu" signal "TOP")
		(4 "In1.Cu" signal "GND")
		(6 "In2.Cu" signal "IN1")
		(8 "In3.Cu" signal "GND1")
		(10 "In4.Cu" signal "VCC")
		(12 "In5.Cu" signal "VCC1")
		(14 "In6.Cu" signal "GND2")
		(16 "In7.Cu" signal "IN2")
		(18 "In8.Cu" signal "GND3")
		(2 "B.Cu" signal "BOTTOM")
		(9 "F.Adhes" user "F.Adhesive")
		(11 "B.Adhes" user "B.Adhesive")
		(13 "F.Paste" user "Package Geometry/Pastemask Top")
		(15 "B.Paste" user "Package Geometry/Pastemask Bottom")
		(5 "F.SilkS" user "Ref Des/Silkscreen Top")
		(7 "B.SilkS" user "Ref Des/Silkscreen Bottom")
		(1 "F.Mask" user "Board Geometry/Soldermask Top")
		(3 "B.Mask" user "Board Geometry/Soldermask Bottom")
		(17 "Dwgs.User" user "User.Drawings")
		(19 "Cmts.User" user "User.Comments")
		(21 "Eco1.User" user "User.Eco1")
		(23 "Eco2.User" user "User.Eco2")
		(25 "Edge.Cuts" user "Board Geometry/Outline")
		(27 "Margin" user)
		(31 "F.CrtYd" user "Package Geometry/Place Bound Top")
		(29 "B.CrtYd" user "Package Geometry/Place Bound Bottom")
		(35 "F.Fab" user "Ref Des/Assembly Top")
		(33 "B.Fab" user "Ref Des/Assembly Bottom")
	)
	(footprint ""
		(layer "B.Cu")
		(at 110.2614 -44.3484 90)
		(property "Reference" "R5868"
			(at 0 0 90)
			(layer "B.SilkS")
			(hide yes)
			(effects
				(font
					(size 1.27 1.27)
				)
				(justify mirror)
			)
		)
		(property "Value" ""
			(at 0 0 90)
			(layer "B.Fab")
			(effects
				(font
					(size 1.27 1.27)
				)
				(justify mirror)
			)
		)
		(duplicate_pad_numbers_are_jumpers no)
		(fp_line
			(start 0.7874 -0.4064)
			(end -0.7874 -0.4064)
			(stroke
				(width 0.1524)
				(type default)
			)
			(layer "B.SilkS")
		)
		(fp_line
			(start -0.7874 -0.4064)
			(end -0.7874 0.4064)
			(stroke
				(width 0.1524)
				(type default)
			)
			(layer "B.SilkS")
		)
		(fp_line
			(start 0.7874 0.4064)
			(end 0.7874 -0.4064)
			(stroke
				(width 0.1524)
				(type default)
			)
			(layer "B.SilkS")
		)
		(fp_line
			(start -0.7874 0.4064)
			(end 0.7874 0.4064)
			(stroke
				(width 0.1524)
				(type default)
			)
			(layer "B.SilkS")
		)
		(fp_line
			(start 0.67945 -0.305054)
			(end 0.12065 -0.305054)
			(stroke
				(width 0.1)
				(type default)
			)
			(layer "B.Fab")
		)
		(fp_line
			(start 0.12065 -0.305054)
			(end 0.12065 -0.2794)
			(stroke
				(width 0.1)
				(type default)
			)
			(layer "B.Fab")
		)
		(fp_line
			(start -0.12065 -0.3048)
			(end -0.67945 -0.3048)
			(stroke
				(width 0.1)
				(type default)
			)
			(layer "B.Fab")
		)
		(fp_line
			(start -0.67945 -0.3048)
			(end -0.67945 0.3048)
			(stroke
				(width 0.1)
				(type default)
			)
			(layer "B.Fab")
		)
		(fp_line
			(start 0.12065 -0.2794)
			(end -0.12065 -0.2794)
			(stroke
				(width 0.1)
				(type default)
			)
			(layer "B.Fab")
		)
		(fp_line
			(start -0.12065 -0.2794)
			(end -0.12065 -0.3048)
			(stroke
				(width 0.1)
				(type default)
			)
			(layer "B.Fab")
		)
		(fp_line
			(start 0.12065 0.2794)
			(end 0.12065 0.3048)
			(stroke
				(width 0.1)
				(type default)
			)
			(layer "B.Fab")
		)
		(fp_line
			(start -0.120396 0.2794)
			(end 0.12065 0.2794)
			(stroke
				(width 0.1)
				(type default)
			)
			(layer "B.Fab")
		)
		(fp_line
			(start 0.67945 0.3048)
			(end 0.67945 -0.305054)
			(stroke
				(width 0.1)
				(type default)
			)
			(layer "B.Fab")
		)
		(fp_line
			(start 0.12065 0.3048)
			(end 0.67945 0.3048)
			(stroke
				(width 0.1)
				(type default)
			)
			(layer "B.Fab")
		)
		(fp_line
			(start -0.120396 0.3048)
			(end -0.120396 0.2794)
			(stroke
				(width 0.1)
				(type default)
			)
			(layer "B.Fab")
		)
		(fp_line
			(start -0.67945 0.3048)
			(end -0.120396 0.3048)
			(stroke
				(width 0.1)
				(type default)
			)
			(layer "B.Fab")
		)
		(pad "1" smd circle
			(at 0.40005 0 270)
			(size 0 0)
			(layers "B.Cu" "B.Mask" "B.Paste")
			(net "P52V_HS2_GATE2_R")
		)
		(pad "2" smd circle
			(at -0.40005 0 270)
			(size 0 0)
			(layers "B.Cu" "B.Mask" "B.Paste")
			(net "P52V_HS2_4287_GATE2_R")
		)
	)
	(footprint ""
		(layer "B.Cu")
		(at 326.7202 -84.1756)
		(property "Reference" ""
			(at 0 0 0)
			(layer "B.SilkS")
			(hide yes)
			(effects
				(font
					(size 1.27 1.27)
				)
				(justify mirror)
			)
		)
		(property "Value" ""
			(at 0 0 0)
			(layer "B.Fab")
			(effects
				(font
					(size 1.27 1.27)
				)
				(justify mirror)
			)
		)
		(duplicate_pad_numbers_are_jumpers no)
		(pad "1" smd circle
			(at 0 0 180)
			(size 0.9906 0.9906)
			(layers "B.Cu" "B.Mask" "B.Paste")
			(net "Net_242")
		)
		(zone
			(layer "B.Cu")
			(hatch none 0.5)
			(connect_pads
				(clearance 0)
			)
			(min_thickness 0.25)
			(keepout
				(tracks not_allowed)
				(vias allowed)
				(pads allowed)
				(copperpour not_allowed)
				(footprints allowed)
			)
			(placement
				(enabled no)
				(sheetname "")
			)
			(fill
				(thermal_gap 0.5)
				(thermal_bridge_width 0.5)
				(island_removal_mode 0)
			)
			(polygon
				(pts
					(arc
						(start 328.3458 -84.1756)
						(mid 325.0946 -84.1756)
						(end 328.3458 -84.1756)
					)
				)
			)
		)
	)
	(footprint ""
		(layer "B.Cu")
		(at 298.069 -92.71 90)
		(property "Reference" "U43"
			(at 2.11963 2.4765 0)
			(unlocked yes)
			(layer "B.SilkS")
			(effects
				(font
					(size 0.7874 0.5842)
					(thickness 0.1524)
				)
				(justify left mirror)
			)
		)
		(property "Value" ""
			(at 0 0 90)
			(layer "B.Fab")
			(effects
				(font
					(size 1.27 1.27)
				)
				(justify mirror)
			)
		)
		(duplicate_pad_numbers_are_jumpers no)
		(fp_line
			(start -1.400048 -1.100074)
			(end 1.400048 -1.100074)
			(stroke
				(width 0.1524)
				(type default)
			)
			(layer "B.SilkS")
		)
		(fp_line
			(start -1.400048 -1.100074)
			(end -1.400048 1.100074)
			(stroke
				(width 0.1524)
				(type default)
			)
			(layer "B.SilkS")
		)
		(fp_line
			(start 1.400048 1.100074)
			(end 1.400048 -1.100074)
			(stroke
				(width 0.1524)
				(type default)
			)
			(layer "B.SilkS")
		)
		(fp_line
			(start -1.400048 1.100074)
			(end 1.400048 1.100074)
			(stroke
				(width 0.1524)
				(type default)
			)
			(layer "B.SilkS")
		)
		(fp_poly
			(pts
				(xy 1.590548 -0.649986) (xy 2.606548 -1.157986) (xy 2.606548 -0.141986)
			)
			(stroke
				(width 0)
				(type default)
			)
			(fill yes)
			(layer "B.SilkS")
		)
		(fp_line
			(start 0.674878 -1.100074)
			(end -0.674878 -1.100074)
			(stroke
				(width 0.1)
				(type default)
			)
			(layer "B.Fab")
		)
		(fp_line
			(start -0.674878 -1.100074)
			(end -0.674878 1.100074)
			(stroke
				(width 0.1)
				(type default)
			)
			(layer "B.Fab")
		)
		(fp_line
			(start 0.674878 1.100074)
			(end 0.674878 -1.100074)
			(stroke
				(width 0.1)
				(type default)
			)
			(layer "B.Fab")
		)
		(fp_line
			(start -0.674878 1.100074)
			(end 0.674878 1.100074)
			(stroke
				(width 0.1)
				(type default)
			)
			(layer "B.Fab")
		)
		(fp_poly
			(pts
				(xy 1.590548 -0.649986) (xy 2.606548 -1.157986) (xy 2.606548 -0.141986)
			)
			(stroke
				(width 0)
				(type default)
			)
			(fill yes)
			(layer "B.Fab")
		)
		(pad "1" smd rect
			(at 0.94996 -0.649986)
			(size 0.4318 0.6096)
			(layers "B.Cu" "B.Mask" "B.Paste")
			(net "Net_417")
		)
		(pad "2" smd rect
			(at 0.94996 0)
			(size 0.4318 0.6096)
			(layers "B.Cu" "B.Mask" "B.Paste")
			(net "FM_HS1_EN_FUSE")
		)
		(pad "3" smd rect
			(at 0.94996 0.649986)
			(size 0.4318 0.6096)
			(layers "B.Cu" "B.Mask" "B.Paste")
			(net "GND")
		)
		(pad "4" smd rect
			(at -0.94996 0.649986)
			(size 0.4318 0.6096)
			(layers "B.Cu" "B.Mask" "B.Paste")
			(net "FM_HS1_EN_FUSE_BUF")
		)
		(pad "5" smd rect
			(at -0.94996 -0.649986)
			(size 0.4318 0.6096)
			(layers "B.Cu" "B.Mask" "B.Paste")
			(net "P3V3_AUX")
		)
	)
	(footprint ""
		(layer "B.Cu")
		(at 276.8854 -76.454 -90)
		(property "Reference" "PC9"
			(at 0 0 90)
			(layer "B.SilkS")
			(hide yes)
			(effects
				(font
					(size 1.27 1.27)
				)
				(justify mirror)
			)
		)
		(property "Value" ""
			(at 0 0 90)
			(layer "B.Fab")
			(effects
				(font
					(size 1.27 1.27)
				)
				(justify mirror)
			)
		)
		(duplicate_pad_numbers_are_jumpers no)
		(fp_line
			(start -0.7874 0.4064)
			(end 0.7874 0.4064)
			(stroke
				(width 0.1524)
				(type default)
			)
			(layer "B.SilkS")
		)
		(fp_line
			(start 0.7874 0.4064)
			(end 0.7874 -0.4064)
			(stroke
				(width 0.1524)
				(type default)
			)
			(layer "B.SilkS")
		)
		(fp_line
			(start -0.7874 -0.4064)
			(end -0.7874 0.4064)
			(stroke
				(width 0.1524)
				(type default)
			)
			(layer "B.SilkS")
		)
		(fp_line
			(start 0.7874 -0.4064)
			(end -0.7874 -0.4064)
			(stroke
				(width 0.1524)
				(type default)
			)
			(layer "B.SilkS")
		)
		(fp_line
			(start -0.67945 0.3048)
			(end -0.120396 0.3048)
			(stroke
				(width 0.1)
				(type default)
			)
			(layer "B.Fab")
		)
		(fp_line
			(start -0.120396 0.3048)
			(end -0.120396 0.2794)
			(stroke
				(width 0.1)
				(type default)
			)
			(layer "B.Fab")
		)
		(fp_line
			(start 0.12065 0.3048)
			(end 0.67945 0.3048)
			(stroke
				(width 0.1)
				(type default)
			)
			(layer "B.Fab")
		)
		(fp_line
			(start 0.67945 0.3048)
			(end 0.67945 -0.305054)
			(stroke
				(width 0.1)
				(type default)
			)
			(layer "B.Fab")
		)
		(fp_line
			(start -0.120396 0.2794)
			(end 0.12065 0.2794)
			(stroke
				(width 0.1)
				(type default)
			)
			(layer "B.Fab")
		)
		(fp_line
			(start 0.12065 0.2794)
			(end 0.12065 0.3048)
			(stroke
				(width 0.1)
				(type default)
			)
			(layer "B.Fab")
		)
		(fp_line
			(start -0.12065 -0.2794)
			(end -0.12065 -0.3048)
			(stroke
				(width 0.1)
				(type default)
			)
			(layer "B.Fab")
		)
		(fp_line
			(start 0.12065 -0.2794)
			(end -0.12065 -0.2794)
			(stroke
				(width 0.1)
				(type default)
			)
			(layer "B.Fab")
		)
		(fp_line
			(start -0.67945 -0.3048)
			(end -0.67945 0.3048)
			(stroke
				(width 0.1)
				(type default)
			)
			(layer "B.Fab")
		)
		(fp_line
			(start -0.12065 -0.3048)
			(end -0.67945 -0.3048)
			(stroke
				(width 0.1)
				(type default)
			)
			(layer "B.Fab")
		)
		(fp_line
			(start 0.12065 -0.305054)
			(end 0.12065 -0.2794)
			(stroke
				(width 0.1)
				(type default)
			)
			(layer "B.Fab")
		)
		(fp_line
			(start 0.67945 -0.305054)
			(end 0.12065 -0.305054)
			(stroke
				(width 0.1)
				(type default)
			)
			(layer "B.Fab")
		)
		(pad "1" smd circle
			(at 0.40005 0 90)
			(size 0 0)
			(layers "B.Cu" "B.Mask" "B.Paste")
			(net "P52V_HS1_RND")
		)
		(pad "2" smd circle
			(at -0.40005 0 90)
			(size 0 0)
			(layers "B.Cu" "B.Mask" "B.Paste")
			(net "GND_FIELD_SIGNAL")
		)
	)
	(footprint ""
		(layer "B.Cu")
		(at 263.6774 -62.738 180)
		(property "Reference" "PR32"
			(at 0 0 0)
			(layer "B.SilkS")
			(hide yes)
			(effects
				(font
					(size 1.27 1.27)
				)
				(justify mirror)
			)
		)
		(property "Value" ""
			(at 0 0 0)
			(layer "B.Fab")
			(effects
				(font
					(size 1.27 1.27)
				)
				(justify mirror)
			)
		)
		(duplicate_pad_numbers_are_jumpers no)
		(fp_line
			(start 1.651 0.8382)
			(end 1.651 -0.8382)
			(stroke
				(width 0.1524)
				(type default)
			)
			(layer "B.SilkS")
		)
		(fp_line
			(start 1.651 -0.8382)
			(end -1.651 -0.8382)
			(stroke
				(width 0.1524)
				(type default)
			)
			(layer "B.SilkS")
		)
		(fp_line
			(start -1.651 0.8382)
			(end 1.651 0.8382)
			(stroke
				(width 0.1524)
				(type default)
			)
			(layer "B.SilkS")
		)
		(fp_line
			(start -1.651 -0.8382)
			(end -1.651 0.8382)
			(stroke
				(width 0.1524)
				(type default)
			)
			(layer "B.SilkS")
		)
		(fp_line
			(start 1.559814 0.7366)
			(end 1.524 0.7366)
			(stroke
				(width 0.1)
				(type default)
			)
			(layer "B.Fab")
		)
		(fp_line
			(start 1.559814 -0.7366)
			(end 1.559814 0.7366)
			(stroke
				(width 0.1)
				(type default)
			)
			(layer "B.Fab")
		)
		(fp_line
			(start 1.524 0.7366)
			(end -1.524 0.7366)
			(stroke
				(width 0.1)
				(type default)
			)
			(layer "B.Fab")
		)
		(fp_line
			(start 1.524 -0.7366)
			(end 1.559814 -0.7366)
			(stroke
				(width 0.1)
				(type default)
			)
			(layer "B.Fab")
		)
		(fp_line
			(start -1.524 0.7366)
			(end -1.560576 0.7366)
			(stroke
				(width 0.1)
				(type default)
			)
			(layer "B.Fab")
		)
		(fp_line
			(start -1.524 -0.7366)
			(end 1.524 -0.7366)
			(stroke
				(width 0.1)
				(type default)
			)
			(layer "B.Fab")
		)
		(fp_line
			(start -1.560576 0.7366)
			(end -1.560576 -0.7366)
			(stroke
				(width 0.1)
				(type default)
			)
			(layer "B.Fab")
		)
		(fp_line
			(start -1.560576 -0.7366)
			(end -1.524 -0.7366)
			(stroke
				(width 0.1)
				(type default)
			)
			(layer "B.Fab")
		)
		(pad "1" smd rect
			(at 0.94996 0 180)
			(size 1.1176 1.3716)
			(layers "B.Cu" "B.Mask" "B.Paste")
			(net "P52V_HS1_DV_DT_R")
		)
		(pad "2" smd rect
			(at -0.94996 0 180)
			(size 1.1176 1.3716)
			(layers "B.Cu" "B.Mask" "B.Paste")
			(net "P52V_HS1_DV_DT")
		)
	)
	(footprint ""
		(layer "B.Cu")
		(at 173.782736 -63.754 90)
		(property "Reference" "PC606"
			(at 0 0 90)
			(layer "B.SilkS")
			(hide yes)
			(effects
				(font
					(size 1.27 1.27)
				)
				(justify mirror)
			)
		)
		(property "Value" ""
			(at 0 0 90)
			(layer "B.Fab")
			(effects
				(font
					(size 1.27 1.27)
				)
				(justify mirror)
			)
		)
		(duplicate_pad_numbers_are_jumpers no)
		(fp_line
			(start 0.7874 -0.4064)
			(end -0.7874 -0.4064)
			(stroke
				(width 0.1524)
				(type default)
			)
			(layer "B.SilkS")
		)
		(fp_line
			(start -0.7874 -0.4064)
			(end -0.7874 0.4064)
			(stroke
				(width 0.1524)
				(type default)
			)
			(layer "B.SilkS")
		)
		(fp_line
			(start 0.7874 0.4064)
			(end 0.7874 -0.4064)
			(stroke
				(width 0.1524)
				(type default)
			)
			(layer "B.SilkS")
		)
		(fp_line
			(start -0.7874 0.4064)
			(end 0.7874 0.4064)
			(stroke
				(width 0.1524)
				(type default)
			)
			(layer "B.SilkS")
		)
		(fp_line
			(start 0.67945 -0.305054)
			(end 0.12065 -0.305054)
			(stroke
				(width 0.1)
				(type default)
			)
			(layer "B.Fab")
		)
		(fp_line
			(start 0.12065 -0.305054)
			(end 0.12065 -0.2794)
			(stroke
				(width 0.1)
				(type default)
			)
			(layer "B.Fab")
		)
		(fp_line
			(start -0.12065 -0.3048)
			(end -0.67945 -0.3048)
			(stroke
				(width 0.1)
				(type default)
			)
			(layer "B.Fab")
		)
		(fp_line
			(start -0.67945 -0.3048)
			(end -0.67945 0.3048)
			(stroke
				(width 0.1)
				(type default)
			)
			(layer "B.Fab")
		)
		(fp_line
			(start 0.12065 -0.2794)
			(end -0.12065 -0.2794)
			(stroke
				(width 0.1)
				(type default)
			)
			(layer "B.Fab")
		)
		(fp_line
			(start -0.12065 -0.2794)
			(end -0.12065 -0.3048)
			(stroke
				(width 0.1)
				(type default)
			)
			(layer "B.Fab")
		)
		(fp_line
			(start 0.12065 0.2794)
			(end 0.12065 0.3048)
			(stroke
				(width 0.1)
				(type default)
			)
			(layer "B.Fab")
		)
		(fp_line
			(start -0.120396 0.2794)
			(end 0.12065 0.2794)
			(stroke
				(width 0.1)
				(type default)
			)
			(layer "B.Fab")
		)
		(fp_line
			(start 0.67945 0.3048)
			(end 0.67945 -0.305054)
			(stroke
				(width 0.1)
				(type default)
			)
			(layer "B.Fab")
		)
		(fp_line
			(start 0.12065 0.3048)
			(end 0.67945 0.3048)
			(stroke
				(width 0.1)
				(type default)
			)
			(layer "B.Fab")
		)
		(fp_line
			(start -0.120396 0.3048)
			(end -0.120396 0.2794)
			(stroke
				(width 0.1)
				(type default)
			)
			(layer "B.Fab")
		)
		(fp_line
			(start -0.67945 0.3048)
			(end -0.120396 0.3048)
			(stroke
				(width 0.1)
				(type default)
			)
			(layer "B.Fab")
		)
		(pad "1" smd circle
			(at 0.40005 0 270)
			(size 0 0)
			(layers "B.Cu" "B.Mask" "B.Paste")
			(net "P52V_HS2_UVH")
		)
		(pad "2" smd circle
			(at -0.40005 0 270)
			(size 0 0)
			(layers "B.Cu" "B.Mask" "B.Paste")
			(net "GND1_FIELD_SIGNAL")
		)
	)
	(footprint ""
		(layer "B.Cu")
		(at 161.717736 -69.469)
		(property "Reference" "PR7012"
			(at 0 0 0)
			(layer "B.SilkS")
			(hide yes)
			(effects
				(font
					(size 1.27 1.27)
				)
				(justify mirror)
			)
		)
		(property "Value" ""
			(at 0 0 0)
			(layer "B.Fab")
			(effects
				(font
					(size 1.27 1.27)
				)
				(justify mirror)
			)
		)
		(duplicate_pad_numbers_are_jumpers no)
		(fp_line
			(start -0.7874 -0.4064)
			(end -0.7874 0.4064)
			(stroke
				(width 0.1524)
				(type default)
			)
			(layer "B.SilkS")
		)
		(fp_line
			(start -0.7874 0.4064)
			(end 0.7874 0.4064)
			(stroke
				(width 0.1524)
				(type default)
			)
			(layer "B.SilkS")
		)
		(fp_line
			(start 0.7874 -0.4064)
			(end -0.7874 -0.4064)
			(stroke
				(width 0.1524)
				(type default)
			)
			(layer "B.SilkS")
		)
		(fp_line
			(start 0.7874 0.4064)
			(end 0.7874 -0.4064)
			(stroke
				(width 0.1524)
				(type default)
			)
			(layer "B.SilkS")
		)
		(fp_line
			(start -0.67945 -0.3048)
			(end -0.67945 0.3048)
			(stroke
				(width 0.1)
				(type default)
			)
			(layer "B.Fab")
		)
		(fp_line
			(start -0.67945 0.3048)
			(end -0.120396 0.3048)
			(stroke
				(width 0.1)
				(type default)
			)
			(layer "B.Fab")
		)
		(fp_line
			(start -0.12065 -0.3048)
			(end -0.67945 -0.3048)
			(stroke
				(width 0.1)
				(type default)
			)
			(layer "B.Fab")
		)
		(fp_line
			(start -0.12065 -0.2794)
			(end -0.12065 -0.3048)
			(stroke
				(width 0.1)
				(type default)
			)
			(layer "B.Fab")
		)
		(fp_line
			(start -0.120396 0.2794)
			(end 0.12065 0.2794)
			(stroke
				(width 0.1)
				(type default)
			)
			(layer "B.Fab")
		)
		(fp_line
			(start -0.120396 0.3048)
			(end -0.120396 0.2794)
			(stroke
				(width 0.1)
				(type default)
			)
			(layer "B.Fab")
		)
		(fp_line
			(start 0.12065 -0.305054)
			(end 0.12065 -0.2794)
			(stroke
				(width 0.1)
				(type default)
			)
			(layer "B.Fab")
		)
		(fp_line
			(start 0.12065 -0.2794)
			(end -0.12065 -0.2794)
			(stroke
				(width 0.1)
				(type default)
			)
			(layer "B.Fab")
		)
		(fp_line
			(start 0.12065 0.2794)
			(end 0.12065 0.3048)
			(stroke
				(width 0.1)
				(type default)
			)
			(layer "B.Fab")
		)
		(fp_line
			(start 0.12065 0.3048)
			(end 0.67945 0.3048)
			(stroke
				(width 0.1)
				(type default)
			)
			(layer "B.Fab")
		)
		(fp_line
			(start 0.67945 -0.305054)
			(end 0.12065 -0.305054)
			(stroke
				(width 0.1)
				(type default)
			)
			(layer "B.Fab")
		)
		(fp_line
			(start 0.67945 0.3048)
			(end 0.67945 -0.305054)
			(stroke
				(width 0.1)
				(type default)
			)
			(layer "B.Fab")
		)
		(pad "1" smd circle
			(at 0.40005 0 180)
			(size 0 0)
			(layers "B.Cu" "B.Mask" "B.Paste")
			(net "GND1_FIELD_SIGNAL")
		)
		(pad "2" smd circle
			(at -0.40005 0 180)
			(size 0 0)
			(layers "B.Cu" "B.Mask" "B.Paste")
			(net "P52V_HS2_CS")
		)
	)
)
